(kicad_pcb
	(version 20260206)
	(generator "pcbnew")
	(generator_version "10.0")
	(general
		(thickness 1.6)
		(legacy_teardrops no)
	)
	(paper "A4")
	(title_block
		(title "netronome-mezz — pcbd0082-001_rev01_jul9_a.brd")
		(comment 1 "Open CloudServer (Microsoft) / footprints 470-475 of 714")
	)
	(layers
		(0 "F.Cu" signal "TOP")
		(4 "In1.Cu" signal "02_GND")
		(6 "In2.Cu" signal "03_SIG")
		(8 "In3.Cu" signal "04_SIG")
		(10 "In4.Cu" signal "05_GND")
		(12 "In5.Cu" signal "06_PWR1")
		(14 "In6.Cu" signal "07_SIG")
		(16 "In7.Cu" signal "08_SIG")
		(18 "In8.Cu" signal "09_GND")
		(2 "B.Cu" signal "BOTTOM")
		(9 "F.Adhes" user "F.Adhesive")
		(11 "B.Adhes" user "B.Adhesive")
		(13 "F.Paste" user "Package Geometry/Pastemask Top")
		(15 "B.Paste" user "Package Geometry/Pastemask Bottom")
		(5 "F.SilkS" user "Ref Des/Silkscreen Top")
		(7 "B.SilkS" user "Ref Des/Silkscreen Bottom")
		(1 "F.Mask" user "Board Geometry/Soldermask Top")
		(3 "B.Mask" user "Board Geometry/Soldermask Bottom")
		(17 "Dwgs.User" user "User.Drawings")
		(19 "Cmts.User" user "User.Comments")
		(21 "Eco1.User" user "User.Eco1")
		(23 "Eco2.User" user "User.Eco2")
		(25 "Edge.Cuts" user "Board Geometry/Outline")
		(27 "Margin" user)
		(31 "F.CrtYd" user "Package Geometry/Place Bound Top")
		(29 "B.CrtYd" user "Package Geometry/Place Bound Bottom")
		(35 "F.Fab" user "Ref Des/Assembly Top")
		(33 "B.Fab" user "Ref Des/Assembly Bottom")
		(45 "User.4" user "COMPVAL_TYPE_BOTTOM")
	)
	(footprint ""
		(layer "B.Cu")
		(at 19.05 45.847 180)
		(property "Reference" "J5"
			(at 9.525 4.6355 0)
			(unlocked yes)
			(layer "B.SilkS")
			(effects
				(font
					(size 1.27 0.9652)
					(thickness 0.1524)
				)
				(justify left mirror)
			)
		)
		(property "Value" "*"
			(at 4.2926 -0.14732 180)
			(unlocked yes)
			(layer "B.Fab")
			(hide yes)
			(effects
				(font
					(size 1.27 0.9652)
					(thickness 0.000001)
				)
				(justify left mirror)
			)
		)
		(property "Device Type" "CONM0077"
			(at 4.2926 -0.14732 180)
			(unlocked yes)
			(layer "B.Fab")
			(hide yes)
			(effects
				(font
					(size 1.27 0.9652)
					(thickness 0.000001)
				)
				(justify left mirror)
			)
		)
		(duplicate_pad_numbers_are_jumpers no)
		(fp_line
			(start 13.081 2.921)
			(end 9.652 2.921)
			(stroke
				(width 0.2032)
				(type default)
			)
			(layer "B.SilkS")
		)
		(fp_line
			(start 13.081 -3.429)
			(end 13.081 2.921)
			(stroke
				(width 0.2032)
				(type default)
			)
			(layer "B.SilkS")
		)
		(fp_line
			(start 11.43 1.778)
			(end 12.065 2.921)
			(stroke
				(width 0.2032)
				(type default)
			)
			(layer "B.SilkS")
		)
		(fp_line
			(start 11.303 -2.921)
			(end 11.303 -3.429)
			(stroke
				(width 0.2032)
				(type default)
			)
			(layer "B.SilkS")
		)
		(fp_line
			(start 11.303 -3.429)
			(end 13.081 -3.429)
			(stroke
				(width 0.2032)
				(type default)
			)
			(layer "B.SilkS")
		)
		(fp_line
			(start 10.795 2.921)
			(end 11.43 1.778)
			(stroke
				(width 0.2032)
				(type default)
			)
			(layer "B.SilkS")
		)
		(fp_line
			(start 9.652 -2.921)
			(end 11.303 -2.921)
			(stroke
				(width 0.2032)
				(type default)
			)
			(layer "B.SilkS")
		)
		(fp_line
			(start -9.652 -2.921)
			(end -11.303 -2.921)
			(stroke
				(width 0.2032)
				(type default)
			)
			(layer "B.SilkS")
		)
		(fp_line
			(start -11.303 -2.921)
			(end -11.303 -3.429)
			(stroke
				(width 0.2032)
				(type default)
			)
			(layer "B.SilkS")
		)
		(fp_line
			(start -11.303 -3.429)
			(end -13.081 -3.429)
			(stroke
				(width 0.2032)
				(type default)
			)
			(layer "B.SilkS")
		)
		(fp_line
			(start -13.081 2.921)
			(end -9.652 2.921)
			(stroke
				(width 0.2032)
				(type default)
			)
			(layer "B.SilkS")
		)
		(fp_line
			(start -13.081 -3.429)
			(end -13.081 2.921)
			(stroke
				(width 0.2032)
				(type default)
			)
			(layer "B.SilkS")
		)
		(fp_circle
			(center 9.906 3.556)
			(end 9.62152 3.556)
			(stroke
				(width 0.2032)
				(type default)
			)
			(fill no)
			(layer "B.SilkS")
		)
		(fp_poly
			(pts
				(xy 13.335 -3.683) (xy 13.335 3.175) (xy 9.906 3.175) (xy 9.906 4.064) (xy -9.906 4.064) (xy -9.906 3.175)
				(xy -13.335 3.175) (xy -13.335 -3.683) (xy -9.906 -3.683) (xy -9.906 -4.064) (xy 9.906 -4.064) (xy 9.906 -3.683)
			)
			(stroke
				(width 0)
				(type default)
			)
			(fill no)
			(layer "B.CrtYd")
		)
		(fp_line
			(start 12.7 2.54)
			(end -12.7 2.54)
			(stroke
				(width 0.2032)
				(type default)
			)
			(layer "B.Fab")
		)
		(fp_line
			(start 12.7 -3.048)
			(end 12.7 2.54)
			(stroke
				(width 0.2032)
				(type default)
			)
			(layer "B.Fab")
		)
		(fp_line
			(start 11.7602 -2.54)
			(end 11.7602 -3.048)
			(stroke
				(width 0.2032)
				(type default)
			)
			(layer "B.Fab")
		)
		(fp_line
			(start 11.7602 -3.048)
			(end 12.7 -3.048)
			(stroke
				(width 0.2032)
				(type default)
			)
			(layer "B.Fab")
		)
		(fp_line
			(start 8.89 1.397)
			(end 9.525 2.54)
			(stroke
				(width 0.2032)
				(type default)
			)
			(layer "B.Fab")
		)
		(fp_line
			(start 8.255 2.54)
			(end 8.89 1.397)
			(stroke
				(width 0.2032)
				(type default)
			)
			(layer "B.Fab")
		)
		(fp_line
			(start 1.27 2.54)
			(end 1.27 1.778)
			(stroke
				(width 0.2032)
				(type default)
			)
			(layer "B.Fab")
		)
		(fp_line
			(start 1.27 1.778)
			(end -1.27 1.778)
			(stroke
				(width 0.2032)
				(type default)
			)
			(layer "B.Fab")
		)
		(fp_line
			(start 1.27 -2.54)
			(end 11.7602 -2.54)
			(stroke
				(width 0.2032)
				(type default)
			)
			(layer "B.Fab")
		)
		(fp_line
			(start 1.27 -3.048)
			(end 1.27 -2.54)
			(stroke
				(width 0.2032)
				(type default)
			)
			(layer "B.Fab")
		)
		(fp_line
			(start -1.27 1.778)
			(end -1.27 2.54)
			(stroke
				(width 0.2032)
				(type default)
			)
			(layer "B.Fab")
		)
		(fp_line
			(start -1.27 -2.54)
			(end -1.27 -3.048)
			(stroke
				(width 0.2032)
				(type default)
			)
			(layer "B.Fab")
		)
		(fp_line
			(start -1.27 -3.048)
			(end 1.27 -3.048)
			(stroke
				(width 0.2032)
				(type default)
			)
			(layer "B.Fab")
		)
		(fp_line
			(start -11.7602 -2.54)
			(end -1.27 -2.54)
			(stroke
				(width 0.2032)
				(type default)
			)
			(layer "B.Fab")
		)
		(fp_line
			(start -11.7602 -3.048)
			(end -11.7602 -2.54)
			(stroke
				(width 0.2032)
				(type default)
			)
			(layer "B.Fab")
		)
		(fp_line
			(start -12.7 2.54)
			(end -12.7 -3.048)
			(stroke
				(width 0.2032)
				(type default)
			)
			(layer "B.Fab")
		)
		(fp_line
			(start -12.7 -3.048)
			(end -11.7602 -3.048)
			(stroke
				(width 0.2032)
				(type default)
			)
			(layer "B.Fab")
		)
		(fp_text user "2"
			(at 9.652 -3.70967 0)
			(unlocked yes)
			(layer "B.SilkS")
			(effects
				(font
					(size 0.7874 0.5842)
					(thickness 0.127)
				)
				(justify left mirror)
			)
		)
		(fp_text user "29"
			(at -10.922 3.65633 0)
			(unlocked yes)
			(layer "B.SilkS")
			(effects
				(font
					(size 0.7874 0.5842)
					(thickness 0.127)
				)
				(justify left mirror)
			)
		)
		(fp_text user "30"
			(at -10.922 -3.58267 0)
			(unlocked yes)
			(layer "B.SilkS")
			(effects
				(font
					(size 0.7874 0.5842)
					(thickness 0.127)
				)
				(justify left mirror)
			)
		)
		(pad "1" smd rect
			(at 8.89 1.9685)
			(size 0.7366 2.921)
			(layers "B.Cu" "B.Mask" "B.Paste")
			(net "CPLD_GPIO_0")
		)
		(pad "2" smd rect
			(at 8.89 -1.9685)
			(size 0.7366 2.921)
			(layers "B.Cu" "B.Mask" "B.Paste")
			(net "CPLD_GPIO_1")
		)
		(pad "3" smd rect
			(at 7.62 1.9685)
			(size 0.7366 2.921)
			(layers "B.Cu" "B.Mask" "B.Paste")
			(net "EXT_3.3V")
		)
		(pad "4" smd rect
			(at 7.62 -1.9685)
			(size 0.7366 2.921)
			(layers "B.Cu" "B.Mask" "B.Paste")
			(net "GND")
		)
		(pad "5" smd rect
			(at 6.35 1.9685)
			(size 0.7366 2.921)
			(layers "B.Cu" "B.Mask" "B.Paste")
			(net "NFP_JTAG_ARM_TCK")
		)
		(pad "6" smd rect
			(at 6.35 -1.9685)
			(size 0.7366 2.921)
			(layers "B.Cu" "B.Mask" "B.Paste")
			(net "PWR_GOOD_LED_L")
		)
		(pad "7" smd rect
			(at 5.08 1.9685)
			(size 0.7366 2.921)
			(layers "B.Cu" "B.Mask" "B.Paste")
			(net "NFP_JTAG_ARM_TDI")
		)
		(pad "8" smd rect
			(at 5.08 -1.9685)
			(size 0.7366 2.921)
			(layers "B.Cu" "B.Mask" "B.Paste")
			(net "PSU_I2C_SCL")
		)
		(pad "9" smd rect
			(at 3.81 1.9685)
			(size 0.7366 2.921)
			(layers "B.Cu" "B.Mask" "B.Paste")
			(net "NFP_JTAG_ARM_TDO")
		)
		(pad "10" smd rect
			(at 3.81 -1.9685)
			(size 0.7366 2.921)
			(layers "B.Cu" "B.Mask" "B.Paste")
			(net "PSU_I2C_SDA")
		)
		(pad "11" smd rect
			(at 2.54 1.9685)
			(size 0.7366 2.921)
			(layers "B.Cu" "B.Mask" "B.Paste")
			(net "NFP_JTAG_ARM_TMS")
		)
		(pad "12" smd rect
			(at 2.54 -1.9685)
			(size 0.7366 2.921)
			(layers "B.Cu" "B.Mask" "B.Paste")
			(net "GND")
		)
		(pad "13" smd rect
			(at 1.27 1.9685)
			(size 0.7366 2.921)
			(layers "B.Cu" "B.Mask" "B.Paste")
			(net "NFP_JTAG_ARM_TRST_L")
		)
		(pad "14" smd rect
			(at 1.27 -1.9685)
			(size 0.7366 2.921)
			(layers "B.Cu" "B.Mask" "B.Paste")
			(net "NFP_FAIL_SAFE_BOOT_L")
		)
		(pad "15" smd rect
			(at 0 1.9685)
			(size 0.7366 2.921)
			(layers "B.Cu" "B.Mask" "B.Paste")
			(net "DEBUG_CPLD_PGRM_JTAG_TCK")
		)
		(pad "16" smd rect
			(at 0 -1.9685)
			(size 0.7366 2.921)
			(layers "B.Cu" "B.Mask" "B.Paste")
			(net "HOST_RESET_REQ_L")
		)
		(pad "17" smd rect
			(at -1.27 1.9685)
			(size 0.7366 2.921)
			(layers "B.Cu" "B.Mask" "B.Paste")
			(net "DEBUG_CPLD_PGRM_JTAG_TDI")
		)
		(pad "18" smd rect
			(at -1.27 -1.9685)
			(size 0.7366 2.921)
			(layers "B.Cu" "B.Mask" "B.Paste")
			(net "CNTRL_SPI_SCK")
		)
		(pad "19" smd rect
			(at -2.54 1.9685)
			(size 0.7366 2.921)
			(layers "B.Cu" "B.Mask" "B.Paste")
			(net "DEBUG_CPLD_PGRM_JTAG_TDO")
		)
		(pad "20" smd rect
			(at -2.54 -1.9685)
			(size 0.7366 2.921)
			(layers "B.Cu" "B.Mask" "B.Paste")
			(net "CNTRL_SPI_MOSI")
		)
		(pad "21" smd rect
			(at -3.81 1.9685)
			(size 0.7366 2.921)
			(layers "B.Cu" "B.Mask" "B.Paste")
			(net "DEBUG_CPLD_PGRM_JTAG_TMS")
		)
		(pad "22" smd rect
			(at -3.81 -1.9685)
			(size 0.7366 2.921)
			(layers "B.Cu" "B.Mask" "B.Paste")
			(net "CNTRL_SPI_MISO")
		)
		(pad "23" smd rect
			(at -5.08 1.9685)
			(size 0.7366 2.921)
			(layers "B.Cu" "B.Mask" "B.Paste")
			(net "NFP_CFG_SPI_FLASH_HOLD_L")
		)
		(pad "24" smd rect
			(at -5.08 -1.9685)
			(size 0.7366 2.921)
			(layers "B.Cu" "B.Mask" "B.Paste")
			(net "CNTRL_SPI_CS")
		)
		(pad "25" smd rect
			(at -6.35 1.9685)
			(size 0.7366 2.921)
			(layers "B.Cu" "B.Mask" "B.Paste")
			(net "NFP_UART_SR_RX")
		)
		(pad "26" smd rect
			(at -6.35 -1.9685)
			(size 0.7366 2.921)
			(layers "B.Cu" "B.Mask" "B.Paste")
			(net "NFP_UART_SR_TX")
		)
		(pad "27" smd rect
			(at -7.62 1.9685)
			(size 0.7366 2.921)
			(layers "B.Cu" "B.Mask" "B.Paste")
			(net "GND")
		)
		(pad "28" smd rect
			(at -7.62 -1.9685)
			(size 0.7366 2.921)
			(layers "B.Cu" "B.Mask" "B.Paste")
			(net "EXT_3.3V")
		)
		(pad "29" smd rect
			(at -8.89 1.9685)
			(size 0.7366 2.921)
			(layers "B.Cu" "B.Mask" "B.Paste")
			(net "CPLD_GPIO_2")
		)
		(pad "30" smd rect
			(at -8.89 -1.9685)
			(size 0.7366 2.921)
			(layers "B.Cu" "B.Mask" "B.Paste")
			(net "CPLD_GPIO_3")
		)
	)
	(footprint ""
		(layer "B.Cu")
		(at 21.971 16.891)
		(property "Reference" "R20"
			(at 0.127 -1.37033 0)
			(unlocked yes)
			(layer "B.SilkS")
			(effects
				(font
					(size 0.7874 0.5842)
					(thickness 0.127)
				)
				(justify left mirror)
			)
		)
		(property "Value" "4.75K"
			(at 0.148158 1.3462 270)
			(unlocked yes)
			(layer "B.Fab")
			(hide yes)
			(effects
				(font
					(size 1.27 0.9652)
					(thickness 0.000001)
				)
				(justify left mirror)
			)
		)
		(property "Device Type" "REST4024"
			(at 0.148158 1.3462 270)
			(unlocked yes)
			(layer "B.Fab")
			(hide yes)
			(effects
				(font
					(size 1.27 0.9652)
					(thickness 0.000001)
				)
				(justify left mirror)
			)
		)
		(duplicate_pad_numbers_are_jumpers no)
		(fp_poly
			(pts
				(xy -0.635 1.0668) (xy -0.635 -1.0668) (xy 0.635 -1.0668) (xy 0.635 1.0668)
			)
			(stroke
				(width 0)
				(type default)
			)
			(fill no)
			(layer "B.CrtYd")
		)
		(fp_line
			(start -0.254 -0.508)
			(end -0.254 0.508)
			(stroke
				(width 0.0254)
				(type default)
			)
			(layer "B.Fab")
		)
		(fp_line
			(start -0.254 0.508)
			(end 0.254 0.508)
			(stroke
				(width 0.0254)
				(type default)
			)
			(layer "B.Fab")
		)
		(fp_line
			(start 0.254 -0.508)
			(end -0.254 -0.508)
			(stroke
				(width 0.0254)
				(type default)
			)
			(layer "B.Fab")
		)
		(fp_line
			(start 0.254 0.508)
			(end 0.254 -0.508)
			(stroke
				(width 0.0254)
				(type default)
			)
			(layer "B.Fab")
		)
		(pad "1" smd rect
			(at 0 -0.4191 180)
			(size 0.508 0.5334)
			(layers "B.Cu" "B.Mask" "B.Paste")
			(net "VDD_3.3V")
		)
		(pad "2" smd rect
			(at 0 0.4191 180)
			(size 0.508 0.5334)
			(layers "B.Cu" "B.Mask" "B.Paste")
			(net "NFP_ARM_SPI_FLASH_MISO")
		)
		(zone
			(layer "B.Cu")
			(hatch none 0.5)
			(connect_pads
				(clearance 0)
			)
			(min_thickness 0.25)
			(keepout
				(tracks not_allowed)
				(vias allowed)
				(pads allowed)
				(copperpour not_allowed)
				(footprints allowed)
			)
			(placement
				(enabled no)
				(sheetname "")
			)
			(fill
				(thermal_gap 0.5)
				(thermal_bridge_width 0.5)
				(island_removal_mode 0)
			)
			(polygon
				(pts
					(xy 21.9456 16.8656) (xy 21.9456 16.9164) (xy 21.9964 16.9164) (xy 21.9964 16.8656)
				)
			)
		)
	)
	(footprint ""
		(layer "B.Cu")
		(at 73.851008 14.256004)
		(property "Reference" "V_A-DM3"
			(at 0 0 0)
			(layer "B.SilkS")
			(hide yes)
			(effects
				(font
					(size 1.27 1.27)
				)
				(justify mirror)
			)
		)
		(property "Value" ""
			(at 0 0 0)
			(layer "B.Fab")
			(effects
				(font
					(size 1.27 1.27)
				)
				(justify mirror)
			)
		)
		(duplicate_pad_numbers_are_jumpers no)
		(pad "1" thru_hole circle
			(at 0 0 180)
			(size 0.4572 0.4572)
			(drill 0.20574)
			(layers "*.Cu" "*.Mask")
			(remove_unused_layers no)
			(net "DDR0_32A_DM3")
			(clearance 0.1143)
			(thermal_gap 0.1143)
		)
	)
	(footprint ""
		(layer "B.Cu")
		(at 40.237029 24.541988 180)
		(property "Reference" "R19"
			(at 0 0 0)
			(layer "B.SilkS")
			(hide yes)
			(effects
				(font
					(size 1.27 1.27)
				)
				(justify mirror)
			)
		)
		(property "Value" ""
			(at 0 0 0)
			(layer "B.Fab")
			(effects
				(font
					(size 1.27 1.27)
				)
				(justify mirror)
			)
		)
		(duplicate_pad_numbers_are_jumpers no)
		(fp_circle
			(center 0 0)
			(end -0.104648 0)
			(stroke
				(width 0.1016)
				(type default)
			)
			(fill no)
			(layer "B.SilkS")
		)
		(fp_poly
			(pts
				(xy 0.381 -0.889) (xy 0.381 0.889) (xy -0.381 0.889) (xy -0.381 -0.889)
			)
			(stroke
				(width 0)
				(type default)
			)
			(fill no)
			(layer "B.CrtYd")
		)
		(fp_line
			(start 0.508 1.016)
			(end 0.508 -1.016)
			(stroke
				(width 0.0254)
				(type default)
			)
			(layer "B.Fab")
		)
		(fp_line
			(start 0.508 -1.016)
			(end 0.254 -1.016)
			(stroke
				(width 0.0254)
				(type default)
			)
			(layer "B.Fab")
		)
		(fp_line
			(start 0.254 -1.016)
			(end -0.508 -1.016)
			(stroke
				(width 0.0254)
				(type default)
			)
			(layer "B.Fab")
		)
		(fp_line
			(start -0.508 1.016)
			(end 0.508 1.016)
			(stroke
				(width 0.0254)
				(type default)
			)
			(layer "B.Fab")
		)
		(fp_line
			(start -0.508 -1.016)
			(end -0.508 1.016)
			(stroke
				(width 0.0254)
				(type default)
			)
			(layer "B.Fab")
		)
		(pad "1" smd custom
			(at 0 -0.500126)
			(size 0.127 0.127)
			(layers "B.Cu" "B.Mask" "B.Paste")
			(net "VDD_3.3V")
			(options
				(clearance outline)
				(anchor circle)
			)
			(primitives
				(gr_poly
					(pts
						(xy -0.1778 0.254) (xy 0.1778 0.254) (xy 0.254 0.1778) (xy 0.254 -0.1778) (xy 0.1778 -0.254) (xy -0.1778 -0.254)
						(xy -0.254 -0.1778) (xy -0.254 0.1778)
					)
					(width 0)
					(fill yes)
				)
			)
		)
		(pad "2" smd custom
			(at 0 0.500126)
			(size 0.127 0.127)
			(layers "B.Cu" "B.Mask" "B.Paste")
			(net "NFP_CLK_NRESET_OUT_L")
			(options
				(clearance outline)
				(anchor circle)
			)
			(primitives
				(gr_poly
					(pts
						(xy -0.1778 0.254) (xy 0.1778 0.254) (xy 0.254 0.1778) (xy 0.254 -0.1778) (xy 0.1778 -0.254) (xy -0.1778 -0.254)
						(xy -0.254 -0.1778) (xy -0.254 0.1778)
					)
					(width 0)
					(fill yes)
				)
			)
		)
	)
	(footprint ""
		(layer "B.Cu")
		(at 81.850992 14.256004)
		(property "Reference" "V2_A-A00"
			(at 0 0 0)
			(layer "B.SilkS")
			(hide yes)
			(effects
				(font
					(size 1.27 1.27)
				)
				(justify mirror)
			)
		)
		(property "Value" ""
			(at 0 0 0)
			(layer "B.Fab")
			(effects
				(font
					(size 1.27 1.27)
				)
				(justify mirror)
			)
		)
		(duplicate_pad_numbers_are_jumpers no)
		(pad "1" thru_hole circle
			(at 0 0 180)
			(size 0.4572 0.4572)
			(drill 0.20574)
			(layers "*.Cu" "*.Mask")
			(remove_unused_layers no)
			(net "DDR0_32A_A0")
			(clearance 0.1143)
			(thermal_gap 0.1143)
		)
	)
	(footprint ""
		(layer "B.Cu")
		(at 77.051002 2.699004)
		(property "Reference" "V_A-DQ04"
			(at 0 0 0)
			(layer "B.SilkS")
			(hide yes)
			(effects
				(font
					(size 1.27 1.27)
				)
				(justify mirror)
			)
		)
		(property "Value" ""
			(at 0 0 0)
			(layer "B.Fab")
			(effects
				(font
					(size 1.27 1.27)
				)
				(justify mirror)
			)
		)
		(duplicate_pad_numbers_are_jumpers no)
		(pad "1" thru_hole circle
			(at 0 0 180)
			(size 0.4572 0.4572)
			(drill 0.20574)
			(layers "*.Cu" "*.Mask")
			(remove_unused_layers no)
			(net "DDR0_32A_DQ4")
			(clearance 0.1143)
			(thermal_gap 0.1143)
		)
	)
)
